# BASEBOARD_FAB2 (Tioga Pass) — schematic netlist excerpt (pin names and nets, part order shuffled) for the footprints in the layout excerpt that follows; sources: Cadence DE-HDL packaged netlist, KiCad conversion of Wiwynn_Tioga_Pass_MB.brd

R7F14  RES  10.0K 1% CHIP  pkg 0402  page 231 : A = FM_PVPP_CPU0_EN ; B = GND
Y8C1  CRYSTAL  25.000MHZ IC  pkg 2013  page 118 : A = XTAL_KR_25M_IN ; B = XTAL_KR_25M_OUT
CT41  CAP  1000PF 50V 10% X7R  pkg 0402LF  page 203 : A = VR_PVCCIN_CPU0_PHASE4 ; B = VR_PVCCIN_CPU0_PHASE4_RC

(kicad_pcb
	(version 20260206)
	(generator "pcbnew")
	(generator_version "10.0")
	(general
		(thickness 1.6)
		(legacy_teardrops no)
	)
	(paper "A4")
	(title_block
		(title "Wiwynn_Tioga_Pass_MB.brd")
		(comment 1 "Tioga Pass / footprints 483-485 of 4770")
	)
	(layers
		(0 "F.Cu" signal "TOP")
		(4 "In1.Cu" signal "L2GND")
		(6 "In2.Cu" signal "L3")
		(8 "In3.Cu" signal "L4GND")
		(10 "In4.Cu" signal "L5")
		(12 "In5.Cu" signal "L6GND")
		(14 "In6.Cu" signal "L7VCC")
		(16 "In7.Cu" signal "L8VCC")
		(18 "In8.Cu" signal "L9GND")
		(20 "In9.Cu" signal "L10")
		(22 "In10.Cu" signal "L11GND")
		(24 "In11.Cu" signal "L12")
		(26 "In12.Cu" signal "L13GND")
		(2 "B.Cu" signal "BOTTOM")
		(9 "F.Adhes" user "F.Adhesive")
		(11 "B.Adhes" user "B.Adhesive")
		(13 "F.Paste" user "Package Geometry/Pastemask Top")
		(15 "B.Paste" user "Package Geometry/Pastemask Bottom")
		(5 "F.SilkS" user "Ref Des/Silkscreen Top")
		(7 "B.SilkS" user "Ref Des/Silkscreen Bottom")
		(1 "F.Mask" user "Board Geometry/Soldermask Top")
		(3 "B.Mask" user "Board Geometry/Soldermask Bottom")
		(17 "Dwgs.User" user "User.Drawings")
		(19 "Cmts.User" user "User.Comments")
		(21 "Eco1.User" user "User.Eco1")
		(23 "Eco2.User" user "User.Eco2")
		(25 "Edge.Cuts" user "Board Geometry/Outline")
		(27 "Margin" user)
		(31 "F.CrtYd" user "Package Geometry/Place Bound Top")
		(29 "B.CrtYd" user "Package Geometry/Place Bound Bottom")
		(35 "F.Fab" user "Ref Des/Assembly Top")
		(33 "B.Fab" user "Ref Des/Assembly Bottom")
	)
	(footprint ""
		(layer "F.Cu")
		(at 408.30373 -100.185982 -90)
		(property "Reference" "Y8C1"
			(at 2.8956 1.09347 270)
			(unlocked yes)
			(layer "F.SilkS")
			(effects
				(font
					(size 0.7874 0.5842)
					(thickness 0.1524)
				)
				(justify left)
			)
		)
		(property "Value" ""
			(at 0 0 270)
			(layer "F.Fab")
			(effects
				(font
					(size 1.27 1.27)
				)
			)
		)
		(duplicate_pad_numbers_are_jumpers no)
		(fp_circle
			(center -0.942594 -0.103378)
			(end -0.942594 -0.230378)
			(stroke
				(width 0.254)
				(type default)
			)
			(fill no)
			(layer "F.SilkS")
		)
		(fp_rect
			(start -0.499872 2.70002)
			(end 2.100072 -0.599948)
			(stroke
				(width 0)
				(type default)
			)
			(fill no)
			(layer "F.CrtYd")
		)
		(fp_line
			(start -0.499872 2.70002)
			(end -0.499872 -0.599948)
			(stroke
				(width 0.1)
				(type default)
			)
			(layer "F.Fab")
		)
		(fp_line
			(start 2.100072 2.70002)
			(end -0.499872 2.70002)
			(stroke
				(width 0.1)
				(type default)
			)
			(layer "F.Fab")
		)
		(fp_line
			(start -0.499872 -0.599948)
			(end 2.100072 -0.599948)
			(stroke
				(width 0.1)
				(type default)
			)
			(layer "F.Fab")
		)
		(fp_line
			(start 2.100072 -0.599948)
			(end 2.100072 2.70002)
			(stroke
				(width 0.1)
				(type default)
			)
			(layer "F.Fab")
		)
		(fp_circle
			(center -1.049782 -0.44323)
			(end -1.049782 -0.57023)
			(stroke
				(width 0.254)
				(type default)
			)
			(fill no)
			(layer "F.Fab")
		)
		(pad "1" smd rect
			(at 0 0 270)
			(size 1.0414 1.143)
			(layers "F.Cu" "F.Mask" "F.Paste")
			(net "XTAL_KR_25M_IN")
		)
		(pad "2" smd rect
			(at 0 2.100072 270)
			(size 1.0414 1.143)
			(layers "F.Cu" "F.Mask" "F.Paste")
			(net "GND")
		)
		(pad "3" smd rect
			(at 1.6002 2.100072 270)
			(size 1.0414 1.143)
			(layers "F.Cu" "F.Mask" "F.Paste")
			(net "XTAL_KR_25M_OUT")
		)
		(pad "4" smd rect
			(at 1.6002 0 270)
			(size 1.0414 1.143)
			(layers "F.Cu" "F.Mask" "F.Paste")
			(net "GND")
		)
	)
	(footprint ""
		(layer "F.Cu")
		(at 340.233 -23.749)
		(property "Reference" "R7F14"
			(at 0 0 0)
			(layer "F.SilkS")
			(hide yes)
			(effects
				(font
					(size 1.27 1.27)
				)
			)
		)
		(property "Value" ""
			(at 0 0 0)
			(layer "F.Fab")
			(effects
				(font
					(size 1.27 1.27)
				)
			)
		)
		(duplicate_pad_numbers_are_jumpers no)
		(fp_rect
			(start -0.2794 0.9906)
			(end 0.2794 -0.1016)
			(stroke
				(width 0)
				(type default)
			)
			(fill no)
			(layer "F.CrtYd")
		)
		(fp_line
			(start -0.2794 -0.1016)
			(end -0.2794 0.9906)
			(stroke
				(width 0.1)
				(type default)
			)
			(layer "F.Fab")
		)
		(fp_line
			(start -0.2794 0.9906)
			(end 0.2794 0.9906)
			(stroke
				(width 0.1)
				(type default)
			)
			(layer "F.Fab")
		)
		(fp_line
			(start 0.2794 -0.1016)
			(end -0.2794 -0.1016)
			(stroke
				(width 0.1)
				(type default)
			)
			(layer "F.Fab")
		)
		(fp_line
			(start 0.2794 0.9906)
			(end 0.2794 -0.1016)
			(stroke
				(width 0.1)
				(type default)
			)
			(layer "F.Fab")
		)
		(pad "1" smd rect
			(at 0 0)
			(size 0.508 0.508)
			(layers "F.Cu" "F.Mask" "F.Paste")
			(net "FM_PVPP_CPU0_EN")
		)
		(pad "2" smd rect
			(at 0 0.889)
			(size 0.508 0.508)
			(layers "F.Cu" "F.Mask" "F.Paste")
			(net "GND")
		)
		(zone
			(layer "F.Cu")
			(hatch none 0.5)
			(connect_pads
				(clearance 0)
			)
			(min_thickness 0.25)
			(keepout
				(tracks allowed)
				(vias not_allowed)
				(pads allowed)
				(copperpour not_allowed)
				(footprints allowed)
			)
			(placement
				(enabled no)
				(sheetname "")
			)
			(fill
				(thermal_gap 0.5)
				(thermal_bridge_width 0.5)
				(island_removal_mode 0)
			)
			(polygon
				(pts
					(xy 339.979 -23.114) (xy 340.487 -23.114) (xy 340.487 -23.495) (xy 339.979 -23.495)
				)
			)
		)
		(zone
			(layer "F.Cu")
			(hatch none 0.5)
			(connect_pads
				(clearance 0)
			)
			(min_thickness 0.25)
			(keepout
				(tracks not_allowed)
				(vias allowed)
				(pads allowed)
				(copperpour not_allowed)
				(footprints allowed)
			)
			(placement
				(enabled no)
				(sheetname "")
			)
			(fill
				(thermal_gap 0.5)
				(thermal_bridge_width 0.5)
				(island_removal_mode 0)
			)
			(polygon
				(pts
					(xy 339.979 -23.114) (xy 340.487 -23.114) (xy 340.487 -23.495) (xy 339.979 -23.495)
				)
			)
		)
	)
	(footprint ""
		(layer "F.Cu")
		(at 204.4192 -77.47 -90)
		(property "Reference" "CT41"
			(at -0.8382 -0.67818 270)
			(unlocked yes)
			(layer "F.SilkS")
			(effects
				(font
					(size 0.4064 0.254)
					(thickness 0.1524)
				)
				(justify left)
			)
		)
		(property "Value" ""
			(at 0 0 270)
			(layer "F.Fab")
			(effects
				(font
					(size 1.27 1.27)
				)
			)
		)
		(duplicate_pad_numbers_are_jumpers no)
		(fp_poly
			(pts
				(xy 0.3048 -0.1016) (xy 0.3048 0.9906) (xy -0.3048 0.9906) (xy -0.3048 -0.1016)
			)
			(stroke
				(width 0)
				(type default)
			)
			(fill no)
			(layer "F.CrtYd")
		)
		(fp_line
			(start -0.3048 0.9906)
			(end 0.3048 0.9906)
			(stroke
				(width 0.1)
				(type default)
			)
			(layer "F.Fab")
		)
		(fp_line
			(start 0.3048 0.9906)
			(end 0.3048 -0.1016)
			(stroke
				(width 0.1)
				(type default)
			)
			(layer "F.Fab")
		)
		(fp_line
			(start -0.3048 -0.1016)
			(end -0.3048 0.9906)
			(stroke
				(width 0.1)
				(type default)
			)
			(layer "F.Fab")
		)
		(fp_line
			(start 0.3048 -0.1016)
			(end -0.3048 -0.1016)
			(stroke
				(width 0.1)
				(type default)
			)
			(layer "F.Fab")
		)
		(pad "1" smd rect
			(at 0 0 270)
			(size 0.508 0.508)
			(layers "F.Cu" "F.Mask" "F.Paste")
			(net "VR_PVCCIN_CPU0_PHASE4")
		)
		(pad "2" smd rect
			(at 0 0.889 270)
			(size 0.508 0.508)
			(layers "F.Cu" "F.Mask" "F.Paste")
			(net "VR_PVCCIN_CPU0_PHASE4_RC")
		)
		(zone
			(layer "F.Cu")
			(hatch none 0.5)
			(connect_pads
				(clearance 0)
			)
			(min_thickness 0.25)
			(keepout
				(tracks not_allowed)
				(vias allowed)
				(pads allowed)
				(copperpour not_allowed)
				(footprints allowed)
			)
			(placement
				(enabled no)
				(sheetname "")
			)
			(fill
				(thermal_gap 0.5)
				(thermal_bridge_width 0.5)
				(island_removal_mode 0)
			)
			(polygon
				(pts
					(xy 203.7842 -77.724) (xy 203.7842 -77.216) (xy 204.1652 -77.216) (xy 204.1652 -77.724)
				)
			)
		)
		(zone
			(layer "F.Cu")
			(hatch none 0.5)
			(connect_pads
				(clearance 0)
			)
			(min_thickness 0.25)
			(keepout
				(tracks allowed)
				(vias not_allowed)
				(pads allowed)
				(copperpour not_allowed)
				(footprints allowed)
			)
			(placement
				(enabled no)
				(sheetname "")
			)
			(fill
				(thermal_gap 0.5)
				(thermal_bridge_width 0.5)
				(island_removal_mode 0)
			)
			(polygon
				(pts
					(xy 204.1652 -77.724) (xy 204.1652 -77.216) (xy 203.7842 -77.216) (xy 203.7842 -77.724)
				)
			)
		)
	)
)
